# T6G (Grand Teton) — schematic netlist excerpt (pin names and nets, part order shuffled) for the footprints in the layout excerpt that follows; sources: Cadence DE-HDL packaged netlist, KiCad conversion of 04192023_DAF0TMB3IC0_F0TG_MB_C_brd_V02_OCP.brd

PR307  Q_RES  0 5% CHIP  pkg 0402LF  page 193 : A = VSENSE_PVDDCR_SOC_P0_DP ; B = VSENSE_PVDDCR_SOC_P0_VSEN1
L6001  Q_INDUCTOR  BLM21PG221SN1D IND  pkg SMLF  page 177 : \1\ = P1V2_AUX ; \2\ = P1V2_CPU0_USB_DVDD12
R687  Q_RES  33.2 1% CHIP  pkg 0201LF  page 311 : A = SMB_RT_CPU0_P3_ROM_R_SCL ; B = SMB_RT_CPU0_P3_ROM_SCL

(kicad_pcb
	(version 20260206)
	(generator "pcbnew")
	(generator_version "10.0")
	(general
		(thickness 1.6)
		(legacy_teardrops no)
	)
	(paper "A4")
	(title_block
		(title "04192023_DAF0TMB3IC0_F0TG_MB_C_brd_V02_OCP.brd")
		(comment 1 "Grand Teton / footprints 7182-7184 of 8354")
	)
	(layers
		(0 "F.Cu" signal "TOP")
		(4 "In1.Cu" signal "GND")
		(6 "In2.Cu" signal "IN1")
		(8 "In3.Cu" signal "GND1")
		(10 "In4.Cu" signal "IN2")
		(12 "In5.Cu" signal "GND2")
		(14 "In6.Cu" signal "IN3")
		(16 "In7.Cu" signal "GND3")
		(18 "In8.Cu" signal "VCC")
		(20 "In9.Cu" signal "VCC1")
		(22 "In10.Cu" signal "GND4")
		(24 "In11.Cu" signal "IN4")
		(26 "In12.Cu" signal "GND5")
		(28 "In13.Cu" signal "IN5")
		(30 "In14.Cu" signal "GND6")
		(32 "In15.Cu" signal "IN6")
		(34 "In16.Cu" signal "GND7")
		(2 "B.Cu" signal "BOTTOM")
		(9 "F.Adhes" user "F.Adhesive")
		(11 "B.Adhes" user "B.Adhesive")
		(13 "F.Paste" user "Package Geometry/Pastemask Top")
		(15 "B.Paste" user "Package Geometry/Pastemask Bottom")
		(5 "F.SilkS" user "Ref Des/Silkscreen Top")
		(7 "B.SilkS" user "Ref Des/Silkscreen Bottom")
		(1 "F.Mask" user "Board Geometry/Soldermask Top")
		(3 "B.Mask" user "Board Geometry/Soldermask Bottom")
		(17 "Dwgs.User" user "User.Drawings")
		(19 "Cmts.User" user "User.Comments")
		(21 "Eco1.User" user "User.Eco1")
		(23 "Eco2.User" user "User.Eco2")
		(25 "Edge.Cuts" user "Board Geometry/Outline")
		(27 "Margin" user)
		(31 "F.CrtYd" user "Package Geometry/Place Bound Top")
		(29 "B.CrtYd" user "Package Geometry/Place Bound Bottom")
		(35 "F.Fab" user "Ref Des/Assembly Top")
		(33 "B.Fab" user "Ref Des/Assembly Bottom")
	)
	(footprint ""
		(layer "B.Cu")
		(at 137.492994 -43.37431)
		(property "Reference" "L6001"
			(at 0 0 0)
			(layer "B.SilkS")
			(hide yes)
			(effects
				(font
					(size 1.27 1.27)
				)
				(justify mirror)
			)
		)
		(property "Value" ""
			(at 0 0 0)
			(layer "B.Fab")
			(effects
				(font
					(size 1.27 1.27)
				)
				(justify mirror)
			)
		)
		(duplicate_pad_numbers_are_jumpers no)
		(fp_line
			(start -1.63576 -0.8128)
			(end -1.63576 0.8128)
			(stroke
				(width 0.1524)
				(type default)
			)
			(layer "B.SilkS")
		)
		(fp_line
			(start -1.63576 0.8128)
			(end 1.63576 0.8128)
			(stroke
				(width 0.1524)
				(type default)
			)
			(layer "B.SilkS")
		)
		(fp_line
			(start 1.63576 -0.8128)
			(end -1.63576 -0.8128)
			(stroke
				(width 0.1524)
				(type default)
			)
			(layer "B.SilkS")
		)
		(fp_line
			(start 1.63576 -0.8128)
			(end 1.63576 0.8128)
			(stroke
				(width 0.1524)
				(type default)
			)
			(layer "B.SilkS")
		)
		(fp_line
			(start -1.560576 -0.738632)
			(end 1.56083 -0.738632)
			(stroke
				(width 0.1)
				(type default)
			)
			(layer "B.Fab")
		)
		(fp_line
			(start -1.560576 0.7366)
			(end -1.560576 -0.738632)
			(stroke
				(width 0.1)
				(type default)
			)
			(layer "B.Fab")
		)
		(fp_line
			(start -1.524 0.7366)
			(end -1.560576 0.7366)
			(stroke
				(width 0.1)
				(type default)
			)
			(layer "B.Fab")
		)
		(fp_line
			(start 1.524 0.7366)
			(end -1.524 0.7366)
			(stroke
				(width 0.1)
				(type default)
			)
			(layer "B.Fab")
		)
		(fp_line
			(start 1.56083 -0.738632)
			(end 1.56083 0.7366)
			(stroke
				(width 0.1)
				(type default)
			)
			(layer "B.Fab")
		)
		(fp_line
			(start 1.56083 0.7366)
			(end 1.524 0.7366)
			(stroke
				(width 0.1)
				(type default)
			)
			(layer "B.Fab")
		)
		(pad "1" smd rect
			(at 0.94996 0)
			(size 1.1176 1.3716)
			(layers "B.Cu" "B.Mask" "B.Paste")
			(net "P1V2_AUX")
		)
		(pad "2" smd rect
			(at -0.94996 0)
			(size 1.1176 1.3716)
			(layers "B.Cu" "B.Mask" "B.Paste")
			(net "P1V2_CPU0_USB_DVDD12")
		)
	)
	(footprint ""
		(layer "B.Cu")
		(at 385.129278 -144.266158)
		(property "Reference" "PR307"
			(at 0 0 0)
			(layer "B.SilkS")
			(hide yes)
			(effects
				(font
					(size 1.27 1.27)
				)
				(justify mirror)
			)
		)
		(property "Value" ""
			(at 0 0 0)
			(layer "B.Fab")
			(effects
				(font
					(size 1.27 1.27)
				)
				(justify mirror)
			)
		)
		(duplicate_pad_numbers_are_jumpers no)
		(fp_line
			(start -0.7874 -0.4064)
			(end -0.7874 0.4064)
			(stroke
				(width 0.1524)
				(type default)
			)
			(layer "B.SilkS")
		)
		(fp_line
			(start -0.7874 0.4064)
			(end 0.7874 0.4064)
			(stroke
				(width 0.1524)
				(type default)
			)
			(layer "B.SilkS")
		)
		(fp_line
			(start 0.7874 -0.4064)
			(end -0.7874 -0.4064)
			(stroke
				(width 0.1524)
				(type default)
			)
			(layer "B.SilkS")
		)
		(fp_line
			(start 0.7874 0.4064)
			(end 0.7874 -0.4064)
			(stroke
				(width 0.1524)
				(type default)
			)
			(layer "B.SilkS")
		)
		(fp_line
			(start -0.67945 -0.3048)
			(end -0.67945 0.3048)
			(stroke
				(width 0.1)
				(type default)
			)
			(layer "B.Fab")
		)
		(fp_line
			(start -0.67945 0.3048)
			(end -0.120396 0.3048)
			(stroke
				(width 0.1)
				(type default)
			)
			(layer "B.Fab")
		)
		(fp_line
			(start -0.12065 -0.3048)
			(end -0.67945 -0.3048)
			(stroke
				(width 0.1)
				(type default)
			)
			(layer "B.Fab")
		)
		(fp_line
			(start -0.12065 -0.2794)
			(end -0.12065 -0.3048)
			(stroke
				(width 0.1)
				(type default)
			)
			(layer "B.Fab")
		)
		(fp_line
			(start -0.120396 0.2794)
			(end 0.12065 0.2794)
			(stroke
				(width 0.1)
				(type default)
			)
			(layer "B.Fab")
		)
		(fp_line
			(start -0.120396 0.3048)
			(end -0.120396 0.2794)
			(stroke
				(width 0.1)
				(type default)
			)
			(layer "B.Fab")
		)
		(fp_line
			(start 0.12065 -0.305054)
			(end 0.12065 -0.2794)
			(stroke
				(width 0.1)
				(type default)
			)
			(layer "B.Fab")
		)
		(fp_line
			(start 0.12065 -0.2794)
			(end -0.12065 -0.2794)
			(stroke
				(width 0.1)
				(type default)
			)
			(layer "B.Fab")
		)
		(fp_line
			(start 0.12065 0.2794)
			(end 0.12065 0.3048)
			(stroke
				(width 0.1)
				(type default)
			)
			(layer "B.Fab")
		)
		(fp_line
			(start 0.12065 0.3048)
			(end 0.67945 0.3048)
			(stroke
				(width 0.1)
				(type default)
			)
			(layer "B.Fab")
		)
		(fp_line
			(start 0.67945 -0.305054)
			(end 0.12065 -0.305054)
			(stroke
				(width 0.1)
				(type default)
			)
			(layer "B.Fab")
		)
		(fp_line
			(start 0.67945 0.3048)
			(end 0.67945 -0.305054)
			(stroke
				(width 0.1)
				(type default)
			)
			(layer "B.Fab")
		)
		(pad "1" smd circle
			(at 0.40005 0 180)
			(size 0 0)
			(layers "B.Cu" "B.Mask" "B.Paste")
			(net "VSENSE_PVDDCR_SOC_P0_DP")
		)
		(pad "2" smd circle
			(at -0.40005 0 180)
			(size 0 0)
			(layers "B.Cu" "B.Mask" "B.Paste")
			(net "VSENSE_PVDDCR_SOC_P0_VSEN1")
		)
	)
	(footprint ""
		(layer "B.Cu")
		(at 368.334798 -424.372786 180)
		(property "Reference" "R687"
			(at 0 0 0)
			(layer "B.SilkS")
			(hide yes)
			(effects
				(font
					(size 1.27 1.27)
				)
				(justify mirror)
			)
		)
		(property "Value" ""
			(at 0 0 0)
			(layer "B.Fab")
			(effects
				(font
					(size 1.27 1.27)
				)
				(justify mirror)
			)
		)
		(duplicate_pad_numbers_are_jumpers no)
		(fp_line
			(start 0.32512 0.175006)
			(end 0.32512 -0.175006)
			(stroke
				(width 0.1)
				(type default)
			)
			(layer "B.Fab")
		)
		(fp_line
			(start 0.32512 -0.175006)
			(end -0.32512 -0.175006)
			(stroke
				(width 0.1)
				(type default)
			)
			(layer "B.Fab")
		)
		(fp_line
			(start -0.32512 0.175006)
			(end 0.32512 0.175006)
			(stroke
				(width 0.1)
				(type default)
			)
			(layer "B.Fab")
		)
		(fp_line
			(start -0.32512 -0.175006)
			(end -0.32512 0.175006)
			(stroke
				(width 0.1)
				(type default)
			)
			(layer "B.Fab")
		)
		(pad "1" smd rect
			(at 0.2667 0)
			(size 0.3048 0.381)
			(layers "B.Cu" "B.Mask" "B.Paste")
			(net "SMB_RT_CPU0_P3_ROM_R_SCL")
		)
		(pad "2" smd rect
			(at -0.2667 0 180)
			(size 0.3048 0.381)
			(layers "B.Cu" "B.Mask" "B.Paste")
			(net "SMB_RT_CPU0_P3_ROM_SCL")
		)
	)
)
